(kicad_pcb
	(version 20260206)
	(generator "pcbnew")
	(generator_version "10.0")
	(general
		(thickness 1.6)
		(legacy_teardrops no)
	)
	(paper "A4")
	(title_block
		(title "Wiwynn_Tioga_Pass_MB.brd")
		(comment 1 "Tioga Pass / footprint 1899 of 4770 (J4G2), pads 124-243 of 291")
	)
	(layers
		(0 "F.Cu" signal "TOP")
		(4 "In1.Cu" signal "L2GND")
		(6 "In2.Cu" signal "L3")
		(8 "In3.Cu" signal "L4GND")
		(10 "In4.Cu" signal "L5")
		(12 "In5.Cu" signal "L6GND")
		(14 "In6.Cu" signal "L7VCC")
		(16 "In7.Cu" signal "L8VCC")
		(18 "In8.Cu" signal "L9GND")
		(20 "In9.Cu" signal "L10")
		(22 "In10.Cu" signal "L11GND")
		(24 "In11.Cu" signal "L12")
		(26 "In12.Cu" signal "L13GND")
		(2 "B.Cu" signal "BOTTOM")
		(9 "F.Adhes" user "F.Adhesive")
		(11 "B.Adhes" user "B.Adhesive")
		(13 "F.Paste" user "Package Geometry/Pastemask Top")
		(15 "B.Paste" user "Package Geometry/Pastemask Bottom")
		(5 "F.SilkS" user "Ref Des/Silkscreen Top")
		(7 "B.SilkS" user "Ref Des/Silkscreen Bottom")
		(1 "F.Mask" user "Board Geometry/Soldermask Top")
		(3 "B.Mask" user "Board Geometry/Soldermask Bottom")
		(17 "Dwgs.User" user "User.Drawings")
		(19 "Cmts.User" user "User.Comments")
		(21 "Eco1.User" user "User.Eco1")
		(23 "Eco2.User" user "User.Eco2")
		(25 "Edge.Cuts" user "Board Geometry/Outline")
		(27 "Margin" user)
		(31 "F.CrtYd" user "Package Geometry/Place Bound Top")
		(29 "B.CrtYd" user "Package Geometry/Place Bound Bottom")
		(35 "F.Fab" user "Ref Des/Assembly Top")
		(33 "B.Fab" user "Ref Des/Assembly Bottom")
	)
	(footprint ""
		(layer "F.Cu")
		(at 194.700398 -5.822442 90)
		(property "Reference" "J4G2"
			(at 6.596888 37.58311 0)
			(unlocked yes)
			(layer "F.SilkS")
			(effects
				(font
					(size 0.7874 0.5842)
					(thickness 0.1524)
				)
				(justify left)
			)
		)
		(property "Value" ""
			(at 0 0 90)
			(layer "F.Fab")
			(effects
				(font
					(size 1.27 1.27)
				)
			)
		)
		(duplicate_pad_numbers_are_jumpers no)
		(pad "121" smd rect
			(at 0 107.100116 90)
			(size 1.8034 0.508)
			(layers "F.Cu" "F.Mask" "F.Paste")
			(net "M_B_DQS_DP<15>")
		)
		(pad "122" smd rect
			(at 0 107.95 90)
			(size 1.8034 0.508)
			(layers "F.Cu" "F.Mask" "F.Paste")
			(net "M_B_DQS_DN<15>")
		)
		(pad "123" smd rect
			(at 0 108.799884 90)
			(size 1.8034 0.508)
			(layers "F.Cu" "F.Mask" "F.Paste")
			(net "GND")
		)
		(pad "124" smd rect
			(at 0 109.650022 90)
			(size 1.8034 0.508)
			(layers "F.Cu" "F.Mask" "F.Paste")
			(net "M_B_DQ<55>")
		)
		(pad "125" smd rect
			(at 0 110.499906 90)
			(size 1.8034 0.508)
			(layers "F.Cu" "F.Mask" "F.Paste")
			(net "GND")
		)
		(pad "126" smd rect
			(at 0 111.350044 90)
			(size 1.8034 0.508)
			(layers "F.Cu" "F.Mask" "F.Paste")
			(net "M_B_DQ<51>")
		)
		(pad "127" smd rect
			(at 0 112.199928 90)
			(size 1.8034 0.508)
			(layers "F.Cu" "F.Mask" "F.Paste")
			(net "GND")
		)
		(pad "128" smd rect
			(at 0 113.050066 90)
			(size 1.8034 0.508)
			(layers "F.Cu" "F.Mask" "F.Paste")
			(net "M_B_DQ<61>")
		)
		(pad "129" smd rect
			(at 0 113.89995 90)
			(size 1.8034 0.508)
			(layers "F.Cu" "F.Mask" "F.Paste")
			(net "GND")
		)
		(pad "130" smd rect
			(at 0 114.750088 90)
			(size 1.8034 0.508)
			(layers "F.Cu" "F.Mask" "F.Paste")
			(net "M_B_DQ<57>")
		)
		(pad "131" smd rect
			(at 0 115.599972 90)
			(size 1.8034 0.508)
			(layers "F.Cu" "F.Mask" "F.Paste")
			(net "GND")
		)
		(pad "132" smd rect
			(at 0 116.45011 90)
			(size 1.8034 0.508)
			(layers "F.Cu" "F.Mask" "F.Paste")
			(net "M_B_DQS_DP<16>")
		)
		(pad "133" smd rect
			(at 0 117.299994 90)
			(size 1.8034 0.508)
			(layers "F.Cu" "F.Mask" "F.Paste")
			(net "M_B_DQS_DN<16>")
		)
		(pad "134" smd rect
			(at 0 118.149878 90)
			(size 1.8034 0.508)
			(layers "F.Cu" "F.Mask" "F.Paste")
			(net "GND")
		)
		(pad "135" smd rect
			(at 0 119.000016 90)
			(size 1.8034 0.508)
			(layers "F.Cu" "F.Mask" "F.Paste")
			(net "M_B_DQ<63>")
		)
		(pad "136" smd rect
			(at 0 119.8499 90)
			(size 1.8034 0.508)
			(layers "F.Cu" "F.Mask" "F.Paste")
			(net "GND")
		)
		(pad "137" smd rect
			(at 0 120.700038 90)
			(size 1.8034 0.508)
			(layers "F.Cu" "F.Mask" "F.Paste")
			(net "M_B_DQ<59>")
		)
		(pad "138" smd rect
			(at 0 121.549922 90)
			(size 1.8034 0.508)
			(layers "F.Cu" "F.Mask" "F.Paste")
			(net "GND")
		)
		(pad "139" smd rect
			(at 0 122.40006 90)
			(size 1.8034 0.508)
			(layers "F.Cu" "F.Mask" "F.Paste")
			(net "GND")
		)
		(pad "140" smd rect
			(at 0 123.249944 90)
			(size 1.8034 0.508)
			(layers "F.Cu" "F.Mask" "F.Paste")
			(net "PVPP_ABC")
		)
		(pad "141" smd rect
			(at 0 124.100082 90)
			(size 1.8034 0.508)
			(layers "F.Cu" "F.Mask" "F.Paste")
			(net "SMB_DDR_ABC_VPP_SCL")
		)
		(pad "142" smd rect
			(at 0 124.949966 90)
			(size 1.8034 0.508)
			(layers "F.Cu" "F.Mask" "F.Paste")
			(net "PVPP_ABC")
		)
		(pad "143" smd rect
			(at 0 125.800104 90)
			(size 1.8034 0.508)
			(layers "F.Cu" "F.Mask" "F.Paste")
			(net "PVPP_ABC")
		)
		(pad "144" smd rect
			(at 0 126.649988 90)
			(size 1.8034 0.508)
			(layers "F.Cu" "F.Mask" "F.Paste")
			(net "TP_CH_B_DIMM_B0_RFU_2")
		)
		(pad "145" smd rect
			(at 4.59994 0 90)
			(size 1.8034 0.508)
			(layers "F.Cu" "F.Mask" "F.Paste")
			(net "P12V_NVDIMM_ABC")
		)
		(pad "146" smd rect
			(at 4.59994 0.849884 90)
			(size 1.8034 0.508)
			(layers "F.Cu" "F.Mask" "F.Paste")
			(net "M_B_VREF")
		)
		(pad "147" smd rect
			(at 4.59994 1.700022 90)
			(size 1.8034 0.508)
			(layers "F.Cu" "F.Mask" "F.Paste")
			(net "GND")
		)
		(pad "148" smd rect
			(at 4.59994 2.549906 90)
			(size 1.8034 0.508)
			(layers "F.Cu" "F.Mask" "F.Paste")
			(net "M_B_DQ<4>")
		)
		(pad "149" smd rect
			(at 4.59994 3.400044 90)
			(size 1.8034 0.508)
			(layers "F.Cu" "F.Mask" "F.Paste")
			(net "GND")
		)
		(pad "150" smd rect
			(at 4.59994 4.249928 90)
			(size 1.8034 0.508)
			(layers "F.Cu" "F.Mask" "F.Paste")
			(net "M_B_DQ<0>")
		)
		(pad "151" smd rect
			(at 4.59994 5.100066 90)
			(size 1.8034 0.508)
			(layers "F.Cu" "F.Mask" "F.Paste")
			(net "GND")
		)
		(pad "152" smd rect
			(at 4.59994 5.94995 90)
			(size 1.8034 0.508)
			(layers "F.Cu" "F.Mask" "F.Paste")
			(net "M_B_DQS_DN<0>")
		)
		(pad "153" smd rect
			(at 4.59994 6.800088 90)
			(size 1.8034 0.508)
			(layers "F.Cu" "F.Mask" "F.Paste")
			(net "M_B_DQS_DP<0>")
		)
		(pad "154" smd rect
			(at 4.59994 7.649972 90)
			(size 1.8034 0.508)
			(layers "F.Cu" "F.Mask" "F.Paste")
			(net "GND")
		)
		(pad "155" smd rect
			(at 4.59994 8.50011 90)
			(size 1.8034 0.508)
			(layers "F.Cu" "F.Mask" "F.Paste")
			(net "M_B_DQ<6>")
		)
		(pad "156" smd rect
			(at 4.59994 9.349994 90)
			(size 1.8034 0.508)
			(layers "F.Cu" "F.Mask" "F.Paste")
			(net "GND")
		)
		(pad "157" smd rect
			(at 4.59994 10.199878 90)
			(size 1.8034 0.508)
			(layers "F.Cu" "F.Mask" "F.Paste")
			(net "M_B_DQ<2>")
		)
		(pad "158" smd rect
			(at 4.59994 11.050016 90)
			(size 1.8034 0.508)
			(layers "F.Cu" "F.Mask" "F.Paste")
			(net "GND")
		)
		(pad "159" smd rect
			(at 4.59994 11.8999 90)
			(size 1.8034 0.508)
			(layers "F.Cu" "F.Mask" "F.Paste")
			(net "M_B_DQ<12>")
		)
		(pad "160" smd rect
			(at 4.59994 12.750038 90)
			(size 1.8034 0.508)
			(layers "F.Cu" "F.Mask" "F.Paste")
			(net "GND")
		)
		(pad "161" smd rect
			(at 4.59994 13.599922 90)
			(size 1.8034 0.508)
			(layers "F.Cu" "F.Mask" "F.Paste")
			(net "M_B_DQ<8>")
		)
		(pad "162" smd rect
			(at 4.59994 14.45006 90)
			(size 1.8034 0.508)
			(layers "F.Cu" "F.Mask" "F.Paste")
			(net "GND")
		)
		(pad "163" smd rect
			(at 4.59994 15.299944 90)
			(size 1.8034 0.508)
			(layers "F.Cu" "F.Mask" "F.Paste")
			(net "M_B_DQS_DN<1>")
		)
		(pad "164" smd rect
			(at 4.59994 16.150082 90)
			(size 1.8034 0.508)
			(layers "F.Cu" "F.Mask" "F.Paste")
			(net "M_B_DQS_DP<1>")
		)
		(pad "165" smd rect
			(at 4.59994 16.999966 90)
			(size 1.8034 0.508)
			(layers "F.Cu" "F.Mask" "F.Paste")
			(net "GND")
		)
		(pad "166" smd rect
			(at 4.59994 17.850104 90)
			(size 1.8034 0.508)
			(layers "F.Cu" "F.Mask" "F.Paste")
			(net "M_B_DQ<14>")
		)
		(pad "167" smd rect
			(at 4.59994 18.699988 90)
			(size 1.8034 0.508)
			(layers "F.Cu" "F.Mask" "F.Paste")
			(net "GND")
		)
		(pad "168" smd rect
			(at 4.59994 19.550126 90)
			(size 1.8034 0.508)
			(layers "F.Cu" "F.Mask" "F.Paste")
			(net "M_B_DQ<10>")
		)
		(pad "169" smd rect
			(at 4.59994 20.40001 90)
			(size 1.8034 0.508)
			(layers "F.Cu" "F.Mask" "F.Paste")
			(net "GND")
		)
		(pad "170" smd rect
			(at 4.59994 21.249894 90)
			(size 1.8034 0.508)
			(layers "F.Cu" "F.Mask" "F.Paste")
			(net "M_B_DQ<20>")
		)
		(pad "171" smd rect
			(at 4.59994 22.100032 90)
			(size 1.8034 0.508)
			(layers "F.Cu" "F.Mask" "F.Paste")
			(net "GND")
		)
		(pad "172" smd rect
			(at 4.59994 22.949916 90)
			(size 1.8034 0.508)
			(layers "F.Cu" "F.Mask" "F.Paste")
			(net "M_B_DQ<16>")
		)
		(pad "173" smd rect
			(at 4.59994 23.800054 90)
			(size 1.8034 0.508)
			(layers "F.Cu" "F.Mask" "F.Paste")
			(net "GND")
		)
		(pad "174" smd rect
			(at 4.59994 24.649938 90)
			(size 1.8034 0.508)
			(layers "F.Cu" "F.Mask" "F.Paste")
			(net "M_B_DQS_DN<2>")
		)
		(pad "175" smd rect
			(at 4.59994 25.500076 90)
			(size 1.8034 0.508)
			(layers "F.Cu" "F.Mask" "F.Paste")
			(net "M_B_DQS_DP<2>")
		)
		(pad "176" smd rect
			(at 4.59994 26.34996 90)
			(size 1.8034 0.508)
			(layers "F.Cu" "F.Mask" "F.Paste")
			(net "GND")
		)
		(pad "177" smd rect
			(at 4.59994 27.200098 90)
			(size 1.8034 0.508)
			(layers "F.Cu" "F.Mask" "F.Paste")
			(net "M_B_DQ<22>")
		)
		(pad "178" smd rect
			(at 4.59994 28.049982 90)
			(size 1.8034 0.508)
			(layers "F.Cu" "F.Mask" "F.Paste")
			(net "GND")
		)
		(pad "179" smd rect
			(at 4.59994 28.90012 90)
			(size 1.8034 0.508)
			(layers "F.Cu" "F.Mask" "F.Paste")
			(net "M_B_DQ<18>")
		)
		(pad "180" smd rect
			(at 4.59994 29.750004 90)
			(size 1.8034 0.508)
			(layers "F.Cu" "F.Mask" "F.Paste")
			(net "GND")
		)
		(pad "181" smd rect
			(at 4.59994 30.599888 90)
			(size 1.8034 0.508)
			(layers "F.Cu" "F.Mask" "F.Paste")
			(net "M_B_DQ<28>")
		)
		(pad "182" smd rect
			(at 4.59994 31.450026 90)
			(size 1.8034 0.508)
			(layers "F.Cu" "F.Mask" "F.Paste")
			(net "GND")
		)
		(pad "183" smd rect
			(at 4.59994 32.29991 90)
			(size 1.8034 0.508)
			(layers "F.Cu" "F.Mask" "F.Paste")
			(net "M_B_DQ<24>")
		)
		(pad "184" smd rect
			(at 4.59994 33.150048 90)
			(size 1.8034 0.508)
			(layers "F.Cu" "F.Mask" "F.Paste")
			(net "GND")
		)
		(pad "185" smd rect
			(at 4.59994 33.999932 90)
			(size 1.8034 0.508)
			(layers "F.Cu" "F.Mask" "F.Paste")
			(net "M_B_DQS_DN<3>")
		)
		(pad "186" smd rect
			(at 4.59994 34.85007 90)
			(size 1.8034 0.508)
			(layers "F.Cu" "F.Mask" "F.Paste")
			(net "M_B_DQS_DP<3>")
		)
		(pad "187" smd rect
			(at 4.59994 35.699954 90)
			(size 1.8034 0.508)
			(layers "F.Cu" "F.Mask" "F.Paste")
			(net "GND")
		)
		(pad "188" smd rect
			(at 4.59994 36.550092 90)
			(size 1.8034 0.508)
			(layers "F.Cu" "F.Mask" "F.Paste")
			(net "M_B_DQ<30>")
		)
		(pad "189" smd rect
			(at 4.59994 37.399976 90)
			(size 1.8034 0.508)
			(layers "F.Cu" "F.Mask" "F.Paste")
			(net "GND")
		)
		(pad "190" smd rect
			(at 4.59994 38.250114 90)
			(size 1.8034 0.508)
			(layers "F.Cu" "F.Mask" "F.Paste")
			(net "M_B_DQ<26>")
		)
		(pad "191" smd rect
			(at 4.59994 39.099998 90)
			(size 1.8034 0.508)
			(layers "F.Cu" "F.Mask" "F.Paste")
			(net "GND")
		)
		(pad "192" smd rect
			(at 4.59994 39.949882 90)
			(size 1.8034 0.508)
			(layers "F.Cu" "F.Mask" "F.Paste")
			(net "M_B_ECC<4>")
		)
		(pad "193" smd rect
			(at 4.59994 40.80002 90)
			(size 1.8034 0.508)
			(layers "F.Cu" "F.Mask" "F.Paste")
			(net "GND")
		)
		(pad "194" smd rect
			(at 4.59994 41.649904 90)
			(size 1.8034 0.508)
			(layers "F.Cu" "F.Mask" "F.Paste")
			(net "M_B_ECC<0>")
		)
		(pad "195" smd rect
			(at 4.59994 42.500042 90)
			(size 1.8034 0.508)
			(layers "F.Cu" "F.Mask" "F.Paste")
			(net "GND")
		)
		(pad "196" smd rect
			(at 4.59994 43.349926 90)
			(size 1.8034 0.508)
			(layers "F.Cu" "F.Mask" "F.Paste")
			(net "M_B_DQS_DN<8>")
		)
		(pad "197" smd rect
			(at 4.59994 44.200064 90)
			(size 1.8034 0.508)
			(layers "F.Cu" "F.Mask" "F.Paste")
			(net "M_B_DQS_DP<8>")
		)
		(pad "198" smd rect
			(at 4.59994 45.049948 90)
			(size 1.8034 0.508)
			(layers "F.Cu" "F.Mask" "F.Paste")
			(net "GND")
		)
		(pad "199" smd rect
			(at 4.59994 45.900086 90)
			(size 1.8034 0.508)
			(layers "F.Cu" "F.Mask" "F.Paste")
			(net "M_B_ECC<6>")
		)
		(pad "200" smd rect
			(at 4.59994 46.74997 90)
			(size 1.8034 0.508)
			(layers "F.Cu" "F.Mask" "F.Paste")
			(net "GND")
		)
		(pad "201" smd rect
			(at 4.59994 47.600108 90)
			(size 1.8034 0.508)
			(layers "F.Cu" "F.Mask" "F.Paste")
			(net "M_B_ECC<2>")
		)
		(pad "202" smd rect
			(at 4.59994 48.449992 90)
			(size 1.8034 0.508)
			(layers "F.Cu" "F.Mask" "F.Paste")
			(net "GND")
		)
		(pad "203" smd rect
			(at 4.59994 49.299876 90)
			(size 1.8034 0.508)
			(layers "F.Cu" "F.Mask" "F.Paste")
			(net "M_B_CKE<1>")
		)
		(pad "204" smd rect
			(at 4.59994 50.150014 90)
			(size 1.8034 0.508)
			(layers "F.Cu" "F.Mask" "F.Paste")
			(net "PVDDQ_ABC")
		)
		(pad "205" smd rect
			(at 4.59994 50.999898 90)
			(size 1.8034 0.508)
			(layers "F.Cu" "F.Mask" "F.Paste")
			(net "TP_CH_B_DIMM_B0_RFU_0")
		)
		(pad "206" smd rect
			(at 4.59994 51.850036 90)
			(size 1.8034 0.508)
			(layers "F.Cu" "F.Mask" "F.Paste")
			(net "PVDDQ_ABC")
		)
		(pad "207" smd rect
			(at 4.59994 52.69992 90)
			(size 1.8034 0.508)
			(layers "F.Cu" "F.Mask" "F.Paste")
			(net "M_B_BG<1>")
		)
		(pad "208" smd rect
			(at 4.59994 53.550058 90)
			(size 1.8034 0.508)
			(layers "F.Cu" "F.Mask" "F.Paste")
			(net "M_B_ALERT_N")
		)
		(pad "209" smd rect
			(at 4.59994 54.399942 90)
			(size 1.8034 0.508)
			(layers "F.Cu" "F.Mask" "F.Paste")
			(net "PVDDQ_ABC")
		)
		(pad "210" smd rect
			(at 4.59994 55.25008 90)
			(size 1.8034 0.508)
			(layers "F.Cu" "F.Mask" "F.Paste")
			(net "M_B_MA<11>")
		)
		(pad "211" smd rect
			(at 4.59994 56.099964 90)
			(size 1.8034 0.508)
			(layers "F.Cu" "F.Mask" "F.Paste")
			(net "M_B_MA<7>")
		)
		(pad "212" smd rect
			(at 4.59994 56.950102 90)
			(size 1.8034 0.508)
			(layers "F.Cu" "F.Mask" "F.Paste")
			(net "PVDDQ_ABC")
		)
		(pad "213" smd rect
			(at 4.59994 57.799986 90)
			(size 1.8034 0.508)
			(layers "F.Cu" "F.Mask" "F.Paste")
			(net "M_B_MA<5>")
		)
		(pad "214" smd rect
			(at 4.59994 58.650124 90)
			(size 1.8034 0.508)
			(layers "F.Cu" "F.Mask" "F.Paste")
			(net "M_B_MA<4>")
		)
		(pad "215" smd rect
			(at 4.59994 59.500008 90)
			(size 1.8034 0.508)
			(layers "F.Cu" "F.Mask" "F.Paste")
			(net "PVDDQ_ABC")
		)
		(pad "216" smd rect
			(at 4.59994 60.349892 90)
			(size 1.8034 0.508)
			(layers "F.Cu" "F.Mask" "F.Paste")
			(net "M_B_MA<2>")
		)
		(pad "217" smd rect
			(at 4.59994 61.20003 90)
			(size 1.8034 0.508)
			(layers "F.Cu" "F.Mask" "F.Paste")
			(net "PVDDQ_ABC")
		)
		(pad "218" smd rect
			(at 4.59994 62.049914 90)
			(size 1.8034 0.508)
			(layers "F.Cu" "F.Mask" "F.Paste")
			(net "M_B_CLK_DP<1>")
		)
		(pad "219" smd rect
			(at 4.59994 62.900052 90)
			(size 1.8034 0.508)
			(layers "F.Cu" "F.Mask" "F.Paste")
			(net "M_B_CLK_DN<1>")
		)
		(pad "220" smd rect
			(at 4.59994 63.749936 90)
			(size 1.8034 0.508)
			(layers "F.Cu" "F.Mask" "F.Paste")
			(net "PVDDQ_ABC")
		)
		(pad "221" smd rect
			(at 4.59994 64.600074 90)
			(size 1.8034 0.508)
			(layers "F.Cu" "F.Mask" "F.Paste")
			(net "PVTT_ABC")
		)
		(pad "222" smd rect
			(at 4.59994 70.550024 90)
			(size 1.8034 0.508)
			(layers "F.Cu" "F.Mask" "F.Paste")
			(net "M_B_PAR")
		)
		(pad "223" smd rect
			(at 4.59994 71.399908 90)
			(size 1.8034 0.508)
			(layers "F.Cu" "F.Mask" "F.Paste")
			(net "PVDDQ_ABC")
		)
		(pad "224" smd rect
			(at 4.59994 72.250046 90)
			(size 1.8034 0.508)
			(layers "F.Cu" "F.Mask" "F.Paste")
			(net "M_B_BA<1>")
		)
		(pad "225" smd rect
			(at 4.59994 73.09993 90)
			(size 1.8034 0.508)
			(layers "F.Cu" "F.Mask" "F.Paste")
			(net "M_B_MA<10>")
		)
		(pad "226" smd rect
			(at 4.59994 73.950068 90)
			(size 1.8034 0.508)
			(layers "F.Cu" "F.Mask" "F.Paste")
			(net "PVDDQ_ABC")
		)
		(pad "227" smd rect
			(at 4.59994 74.799952 90)
			(size 1.8034 0.508)
			(layers "F.Cu" "F.Mask" "F.Paste")
			(net "TP_CH_B_DIMM_B0_RFU_1")
		)
		(pad "228" smd rect
			(at 4.59994 75.65009 90)
			(size 1.8034 0.508)
			(layers "F.Cu" "F.Mask" "F.Paste")
			(net "M_B_MA<14>")
		)
		(pad "229" smd rect
			(at 4.59994 76.499974 90)
			(size 1.8034 0.508)
			(layers "F.Cu" "F.Mask" "F.Paste")
			(net "PVDDQ_ABC")
		)
		(pad "230" smd rect
			(at 4.59994 77.350112 90)
			(size 1.8034 0.508)
			(layers "F.Cu" "F.Mask" "F.Paste")
			(net "FM_ADR_COMPLETE_ABC_N")
		)
		(pad "231" smd rect
			(at 4.59994 78.199996 90)
			(size 1.8034 0.508)
			(layers "F.Cu" "F.Mask" "F.Paste")
			(net "PVDDQ_ABC")
		)
		(pad "232" smd rect
			(at 4.59994 79.04988 90)
			(size 1.8034 0.508)
			(layers "F.Cu" "F.Mask" "F.Paste")
			(net "M_B_MA<13>")
		)
		(pad "233" smd rect
			(at 4.59994 79.900018 90)
			(size 1.8034 0.508)
			(layers "F.Cu" "F.Mask" "F.Paste")
			(net "PVDDQ_ABC")
		)
		(pad "234" smd rect
			(at 4.59994 80.749902 90)
			(size 1.8034 0.508)
			(layers "F.Cu" "F.Mask" "F.Paste")
			(net "M_B_MA<17>")
		)
		(pad "235" smd rect
			(at 4.59994 81.60004 90)
			(size 1.8034 0.508)
			(layers "F.Cu" "F.Mask" "F.Paste")
			(net "M_B_C<2>")
		)
		(pad "236" smd rect
			(at 4.59994 82.449924 90)
			(size 1.8034 0.508)
			(layers "F.Cu" "F.Mask" "F.Paste")
			(net "PVDDQ_ABC")
		)
		(pad "237" smd rect
			(at 4.59994 83.300062 90)
			(size 1.8034 0.508)
			(layers "F.Cu" "F.Mask" "F.Paste")
			(net "M_B_CS_N<3>")
		)
		(pad "238" smd rect
			(at 4.59994 84.149946 90)
			(size 1.8034 0.508)
			(layers "F.Cu" "F.Mask" "F.Paste")
			(net "GND")
		)
		(pad "239" smd rect
			(at 4.59994 85.000084 90)
			(size 1.8034 0.508)
			(layers "F.Cu" "F.Mask" "F.Paste")
			(net "GND")
		)
		(pad "240" smd rect
			(at 4.59994 85.849968 90)
			(size 1.8034 0.508)
			(layers "F.Cu" "F.Mask" "F.Paste")
			(net "M_B_DQ<36>")
		)
	)
)
